(kicad_pcb
	(version 20241229)
	(generator "pcbnew")
	(generator_version "9.0")
	(general
		(thickness 1.61)
		(legacy_teardrops no)
	)
	(paper "A3")
	(title_block
		(title "SO-DIMM DDR5 Tester")
		(date "2025-11-26")
		(rev "1.3.0")
		(comment 9 "footprint 59 of 627 (U4), pads 286-354 of 676")
	)
	(layers
		(0 "F.Cu" signal)
		(4 "In1.Cu" power)
		(6 "In2.Cu" mixed)
		(8 "In3.Cu" power)
		(10 "In4.Cu" mixed)
		(12 "In5.Cu" power)
		(14 "In6.Cu" mixed)
		(16 "In7.Cu" power)
		(18 "In8.Cu" power)
		(20 "In9.Cu" mixed)
		(22 "In10.Cu" power)
		(2 "B.Cu" signal)
		(9 "F.Adhes" user "F.Adhesive")
		(11 "B.Adhes" user "B.Adhesive")
		(13 "F.Paste" user)
		(15 "B.Paste" user)
		(5 "F.SilkS" user "F.Silkscreen")
		(7 "B.SilkS" user "B.Silkscreen")
		(1 "F.Mask" user)
		(3 "B.Mask" user)
		(17 "Dwgs.User" user "User.Drawings")
		(19 "Cmts.User" user "User.Comments")
		(21 "Eco1.User" user "User.Eco1")
		(23 "Eco2.User" user "User.Eco2")
		(25 "Edge.Cuts" user)
		(27 "Margin" user)
		(31 "F.CrtYd" user "F.Courtyard")
		(29 "B.CrtYd" user "B.Courtyard")
		(35 "F.Fab" user)
		(33 "B.Fab" user)
	)
	(footprint "antmicro-footprints:BGA-676_27x27mm_Layout26x26_P1x1mm_FFG676"
		(layer "F.Cu")
		(at 138.875501 174.801 180)
		(descr "FPGA XC7K160TFBG676")
		(tags "FPGA XC7K160TFBG676")
		(property "Reference" "U4"
			(at -12.224499 14.051 180)
			(layer "F.SilkS")
			(effects
				(font
					(size 0.7 0.7)
					(thickness 0.15)
				)
				(justify left bottom)
			)
		)
		(property "Value" "XC7K160T-FFG676"
			(at 0 15.5 180)
			(layer "F.Fab")
			(effects
				(font
					(size 0.7 0.7)
					(thickness 0.15)
				)
				(justify left bottom)
			)
		)
		(property "Datasheet" "https://docs.xilinx.com/v/u/en-US/ds180_7Series_Overview"
			(at 0 0 180)
			(layer "F.Fab")
			(hide yes)
			(effects
				(font
					(size 1.27 1.27)
					(thickness 0.15)
				)
			)
		)
		(property "Author" "Antmicro"
			(at 277.751002 349.602 0)
			(layer "F.Fab")
			(hide yes)
			(effects
				(font
					(size 1 1)
					(thickness 0.15)
				)
			)
		)
		(property "License" "Apache-2.0"
			(at 277.751002 349.602 0)
			(layer "F.Fab")
			(hide yes)
			(effects
				(font
					(size 1 1)
					(thickness 0.15)
				)
			)
		)
		(property "MPN" "XC7K160T-FFG676"
			(at 277.751002 349.602 0)
			(layer "F.Fab")
			(hide yes)
			(effects
				(font
					(size 1 1)
					(thickness 0.15)
				)
			)
		)
		(property "Manufacturer" "AMD-Xilinx"
			(at 277.751002 349.602 0)
			(layer "F.Fab")
			(hide yes)
			(effects
				(font
					(size 1 1)
					(thickness 0.15)
				)
			)
		)
		(sheetname "/FPGA Config/")
		(sheetfile "fpga-config.kicad_sch")
		(attr smd)
		(pad "E26" smd circle
			(at 12.499 -8.5 180)
			(size 0.5 0.5)
			(layers "F.Cu" "F.Mask" "F.Paste")
			(net 641 "/Debug FTDI/UART0.TX")
			(pinfunction "IO_L17N_T2_A13_D29_14")
			(pintype "bidirectional")
			(die_length 20.928)
		)
		(pad "F1" smd circle
			(at -12.5 -7.5 180)
			(size 0.5 0.5)
			(layers "F.Cu" "F.Mask" "F.Paste")
			(net 25 "/FPGA MGT Interface/GTX_TX0_N")
			(pinfunction "MGTXTXN0_116")
			(pintype "bidirectional")
			(die_length 14.583)
		)
		(pad "F2" smd circle
			(at -11.5 -7.5 180)
			(size 0.5 0.5)
			(layers "F.Cu" "F.Mask" "F.Paste")
			(net 17 "/FPGA MGT Interface/GTX_TX0_P")
			(pinfunction "MGTXTXP0_116")
			(pintype "bidirectional")
			(die_length 14.603)
		)
		(pad "F3" smd circle
			(at -10.5 -7.5 180)
			(size 0.5 0.5)
			(layers "F.Cu" "F.Mask" "F.Paste")
			(net 1 "GND")
			(pinfunction "GND")
			(pintype "passive")
		)
		(pad "F4" smd circle
			(at -9.5 -7.5 180)
			(size 0.5 0.5)
			(layers "F.Cu" "F.Mask" "F.Paste")
			(net 1 "GND")
			(pinfunction "GND")
			(pintype "passive")
		)
		(pad "F5" smd circle
			(at -8.5 -7.5 180)
			(size 0.5 0.5)
			(layers "F.Cu" "F.Mask" "F.Paste")
			(net 431 "unconnected-(U4I-MGTREFCLK1N_116-PadF5)")
			(pinfunction "MGTREFCLK1N_116")
			(pintype "bidirectional+no_connect")
			(die_length 12.724)
		)
		(pad "F6" smd circle
			(at -7.5 -7.5 180)
			(size 0.5 0.5)
			(layers "F.Cu" "F.Mask" "F.Paste")
			(net 432 "unconnected-(U4I-MGTREFCLK1P_116-PadF6)")
			(pinfunction "MGTREFCLK1P_116")
			(pintype "bidirectional+no_connect")
			(die_length 13.203)
		)
		(pad "F7" smd circle
			(at -6.5 -7.5 180)
			(size 0.5 0.5)
			(layers "F.Cu" "F.Mask" "F.Paste")
			(net 1 "GND")
			(pinfunction "GND")
			(pintype "passive")
		)
		(pad "F8" smd circle
			(at -5.5 -7.5 180)
			(size 0.5 0.5)
			(layers "F.Cu" "F.Mask" "F.Paste")
			(net 594 "/FPGA bank 16/SD.DAT1")
			(pinfunction "IO_L7N_T1_16")
			(pintype "bidirectional")
			(die_length 17.801)
		)
		(pad "F9" smd circle
			(at -4.5 -7.5 180)
			(size 0.5 0.5)
			(layers "F.Cu" "F.Mask" "F.Paste")
			(net 669 "/FPGA bank 16/SD.CD")
			(pinfunction "IO_L7P_T1_16")
			(pintype "bidirectional")
			(die_length 16.924)
		)
		(pad "F10" smd circle
			(at -3.5 -7.5 180)
			(size 0.5 0.5)
			(layers "F.Cu" "F.Mask" "F.Paste")
			(net 433 "unconnected-(U4E-IO_L11N_T1_SRCC_16-PadF10)")
			(pinfunction "IO_L11N_T1_SRCC_16")
			(pintype "bidirectional+no_connect")
			(die_length 15.436)
		)
		(pad "F11" smd circle
			(at -2.5 -7.5 180)
			(size 0.5 0.5)
			(layers "F.Cu" "F.Mask" "F.Paste")
			(net 1 "GND")
			(pinfunction "GND")
			(pintype "passive")
		)
		(pad "F12" smd circle
			(at -1.5 -7.5 180)
			(size 0.5 0.5)
			(layers "F.Cu" "F.Mask" "F.Paste")
			(net 434 "unconnected-(U4E-IO_L16N_T2_16-PadF12)")
			(pinfunction "IO_L16N_T2_16")
			(pintype "bidirectional+no_connect")
			(die_length 13.211)
		)
		(pad "F13" smd circle
			(at -0.5 -7.5 180)
			(size 0.5 0.5)
			(layers "F.Cu" "F.Mask" "F.Paste")
			(net 435 "unconnected-(U4E-IO_L15N_T2_DQS_16-PadF13)")
			(pinfunction "IO_L15N_T2_DQS_16")
			(pintype "bidirectional+no_connect")
			(die_length 15.248)
		)
		(pad "F14" smd circle
			(at 0.499 -7.5 180)
			(size 0.5 0.5)
			(layers "F.Cu" "F.Mask" "F.Paste")
			(net 436 "unconnected-(U4E-IO_L15P_T2_DQS_16-PadF14)")
			(pinfunction "IO_L15P_T2_DQS_16")
			(pintype "bidirectional+no_connect")
			(die_length 15.557)
		)
		(pad "F15" smd circle
			(at 1.499 -7.5 180)
			(size 0.5 0.5)
			(layers "F.Cu" "F.Mask" "F.Paste")
			(net 437 "unconnected-(U4D-IO_L8N_T1_AD3N_15-PadF15)")
			(pinfunction "IO_L8N_T1_AD3N_15")
			(pintype "bidirectional+no_connect")
			(die_length 18.872)
		)
		(pad "F16" smd circle
			(at 2.499 -7.5 180)
			(size 0.5 0.5)
			(layers "F.Cu" "F.Mask" "F.Paste")
			(net 377 "Net-(R97-Pad2)")
			(pinfunction "VCCO_15")
			(pintype "passive")
		)
		(pad "F17" smd circle
			(at 3.499 -7.5 180)
			(size 0.5 0.5)
			(layers "F.Cu" "F.Mask" "F.Paste")
			(net 438 "unconnected-(U4D-IO_L12P_T1_MRCC_AD5P_15-PadF17)")
			(pinfunction "IO_L12P_T1_MRCC_AD5P_15")
			(pintype "bidirectional+no_connect")
			(die_length 13.832)
		)
		(pad "F18" smd circle
			(at 4.499 -7.5 180)
			(size 0.5 0.5)
			(layers "F.Cu" "F.Mask" "F.Paste")
			(net 439 "unconnected-(U4D-IO_L11N_T1_SRCC_AD12N_15-PadF18)")
			(pinfunction "IO_L11N_T1_SRCC_AD12N_15")
			(pintype "bidirectional+no_connect")
			(die_length 12.908)
		)
		(pad "F19" smd circle
			(at 5.499 -7.5 180)
			(size 0.5 0.5)
			(layers "F.Cu" "F.Mask" "F.Paste")
			(net 440 "unconnected-(U4D-IO_L17P_T2_A26_15-PadF19)")
			(pinfunction "IO_L17P_T2_A26_15")
			(pintype "bidirectional+no_connect")
			(die_length 14.191)
		)
		(pad "F20" smd circle
			(at 6.499 -7.5 180)
			(size 0.5 0.5)
			(layers "F.Cu" "F.Mask" "F.Paste")
			(net 441 "unconnected-(U4D-IO_L16N_T2_A27_15-PadF20)")
			(pinfunction "IO_L16N_T2_A27_15")
			(pintype "bidirectional+no_connect")
			(die_length 12.487)
		)
		(pad "F21" smd circle
			(at 7.499 -7.5 180)
			(size 0.5 0.5)
			(layers "F.Cu" "F.Mask" "F.Paste")
			(net 1 "GND")
			(pinfunction "GND")
			(pintype "passive")
		)
		(pad "F22" smd circle
			(at 8.499 -7.5 180)
			(size 0.5 0.5)
			(layers "F.Cu" "F.Mask" "F.Paste")
			(net 442 "unconnected-(U4C-IO_L12P_T1_MRCC_14-PadF22)")
			(pinfunction "IO_L12P_T1_MRCC_14")
			(pintype "bidirectional+no_connect")
			(die_length 19.515)
		)
		(pad "F23" smd circle
			(at 9.499 -7.5 180)
			(size 0.5 0.5)
			(layers "F.Cu" "F.Mask" "F.Paste")
			(net 242 "FPGA_POWER_OFF")
			(pinfunction "IO_L13N_T2_MRCC_14")
			(pintype "bidirectional")
			(die_length 17.933)
		)
		(pad "F24" smd circle
			(at 10.499 -7.5 180)
			(size 0.5 0.5)
			(layers "F.Cu" "F.Mask" "F.Paste")
			(net 443 "unconnected-(U4C-IO_L14N_T2_SRCC_14-PadF24)")
			(pinfunction "IO_L14N_T2_SRCC_14")
			(pintype "bidirectional+no_connect")
			(die_length 19.105)
		)
		(pad "F25" smd circle
			(at 11.499 -7.5 180)
			(size 0.5 0.5)
			(layers "F.Cu" "F.Mask" "F.Paste")
			(net 639 "/Debug FTDI/UART0.RX")
			(pinfunction "IO_L17P_T2_A14_D30_14")
			(pintype "bidirectional")
			(die_length 19.892)
		)
		(pad "F26" smd circle
			(at 12.499 -7.5 180)
			(size 0.5 0.5)
			(layers "F.Cu" "F.Mask" "F.Paste")
			(net 200 "+3V3")
			(pinfunction "VCCO_14")
			(pintype "passive")
		)
		(pad "G1" smd circle
			(at -12.5 -6.5 180)
			(size 0.5 0.5)
			(layers "F.Cu" "F.Mask" "F.Paste")
			(net 1 "GND")
			(pinfunction "GND")
			(pintype "passive")
		)
		(pad "G2" smd circle
			(at -11.5 -6.5 180)
			(size 0.5 0.5)
			(layers "F.Cu" "F.Mask" "F.Paste")
			(net 226 "+1V2_MGTAVTT")
			(pinfunction "MGTAVTT")
			(pintype "passive")
		)
		(pad "G3" smd circle
			(at -10.5 -6.5 180)
			(size 0.5 0.5)
			(layers "F.Cu" "F.Mask" "F.Paste")
			(net 611 "/FPGA MGT Interface/PCIE.RXD3_N")
			(pinfunction "MGTXRXN0_116")
			(pintype "bidirectional")
			(die_length 12.486)
		)
		(pad "G4" smd circle
			(at -9.5 -6.5 180)
			(size 0.5 0.5)
			(layers "F.Cu" "F.Mask" "F.Paste")
			(net 610 "/FPGA MGT Interface/PCIE.RXD3_P")
			(pinfunction "MGTXRXP0_116")
			(pintype "bidirectional")
			(die_length 12.584)
		)
		(pad "G5" smd circle
			(at -8.5 -6.5 180)
			(size 0.5 0.5)
			(layers "F.Cu" "F.Mask" "F.Paste")
			(net 1 "GND")
			(pinfunction "GND")
			(pintype "passive")
		)
		(pad "G6" smd circle
			(at -7.5 -6.5 180)
			(size 0.5 0.5)
			(layers "F.Cu" "F.Mask" "F.Paste")
			(net 187 "+1V0_MGTAVCC")
			(pinfunction "MGTAVCC")
			(pintype "passive")
		)
		(pad "G7" smd circle
			(at -6.5 -6.5 180)
			(size 0.5 0.5)
			(layers "F.Cu" "F.Mask" "F.Paste")
			(net 614 "/FPGA Config/INIT_B")
			(pinfunction "INIT_B_0")
			(pintype "bidirectional")
			(die_length 30.602)
		)
		(pad "G8" smd circle
			(at -5.5 -6.5 180)
			(size 0.5 0.5)
			(layers "F.Cu" "F.Mask" "F.Paste")
			(net 1 "GND")
			(pinfunction "GND")
			(pintype "passive")
		)
		(pad "G9" smd circle
			(at -4.5 -6.5 180)
			(size 0.5 0.5)
			(layers "F.Cu" "F.Mask" "F.Paste")
			(net 444 "unconnected-(U4E-IO_L2N_T0_16-PadG9)")
			(pinfunction "IO_L2N_T0_16")
			(pintype "bidirectional+no_connect")
			(die_length 14.946)
		)
		(pad "G10" smd circle
			(at -3.5 -6.5 180)
			(size 0.5 0.5)
			(layers "F.Cu" "F.Mask" "F.Paste")
			(net 445 "unconnected-(U4E-IO_L2P_T0_16-PadG10)")
			(pinfunction "IO_L2P_T0_16")
			(pintype "bidirectional+no_connect")
			(die_length 13.481)
		)
		(pad "G11" smd circle
			(at -2.5 -6.5 180)
			(size 0.5 0.5)
			(layers "F.Cu" "F.Mask" "F.Paste")
			(net 446 "unconnected-(U4E-IO_L11P_T1_SRCC_16-PadG11)")
			(pinfunction "IO_L11P_T1_SRCC_16")
			(pintype "bidirectional+no_connect")
			(die_length 14.905)
		)
		(pad "G12" smd circle
			(at -1.5 -6.5 180)
			(size 0.5 0.5)
			(layers "F.Cu" "F.Mask" "F.Paste")
			(net 447 "unconnected-(U4E-IO_L16P_T2_16-PadG12)")
			(pinfunction "IO_L16P_T2_16")
			(pintype "bidirectional+no_connect")
			(die_length 13.211)
		)
		(pad "G13" smd circle
			(at -0.5 -6.5 180)
			(size 0.5 0.5)
			(layers "F.Cu" "F.Mask" "F.Paste")
			(net 200 "+3V3")
			(pinfunction "VCCO_16")
			(pintype "passive")
		)
		(pad "G14" smd circle
			(at 0.499 -6.5 180)
			(size 0.5 0.5)
			(layers "F.Cu" "F.Mask" "F.Paste")
			(net 448 "unconnected-(U4E-IO_L5N_T0_16-PadG14)")
			(pinfunction "IO_L5N_T0_16")
			(pintype "bidirectional+no_connect")
			(die_length 10.327)
		)
		(pad "G15" smd circle
			(at 1.499 -6.5 180)
			(size 0.5 0.5)
			(layers "F.Cu" "F.Mask" "F.Paste")
			(net 449 "unconnected-(U4D-IO_L8P_T1_AD3P_15-PadG15)")
			(pinfunction "IO_L8P_T1_AD3P_15")
			(pintype "bidirectional+no_connect")
			(die_length 19.124)
		)
		(pad "G16" smd circle
			(at 2.499 -6.5 180)
			(size 0.5 0.5)
			(layers "F.Cu" "F.Mask" "F.Paste")
			(net 450 "unconnected-(U4D-IO_L7N_T1_AD10N_15-PadG16)")
			(pinfunction "IO_L7N_T1_AD10N_15")
			(pintype "bidirectional+no_connect")
			(die_length 13.719)
		)
		(pad "G17" smd circle
			(at 3.499 -6.5 180)
			(size 0.5 0.5)
			(layers "F.Cu" "F.Mask" "F.Paste")
			(net 451 "unconnected-(U4D-IO_L11P_T1_SRCC_AD12P_15-PadG17)")
			(pinfunction "IO_L11P_T1_SRCC_AD12P_15")
			(pintype "bidirectional+no_connect")
			(die_length 12.537)
		)
		(pad "G18" smd circle
			(at 4.499 -6.5 180)
			(size 0.5 0.5)
			(layers "F.Cu" "F.Mask" "F.Paste")
			(net 1 "GND")
			(pinfunction "GND")
			(pintype "passive")
		)
		(pad "G19" smd circle
			(at 5.499 -6.5 180)
			(size 0.5 0.5)
			(layers "F.Cu" "F.Mask" "F.Paste")
			(net 452 "unconnected-(U4D-IO_L16P_T2_A28_15-PadG19)")
			(pinfunction "IO_L16P_T2_A28_15")
			(pintype "bidirectional+no_connect")
			(die_length 12.445)
		)
		(pad "G20" smd circle
			(at 6.499 -6.5 180)
			(size 0.5 0.5)
			(layers "F.Cu" "F.Mask" "F.Paste")
			(net 453 "unconnected-(U4D-IO_L18N_T2_A23_15-PadG20)")
			(pinfunction "IO_L18N_T2_A23_15")
			(pintype "bidirectional+no_connect")
			(die_length 11.544)
		)
		(pad "G21" smd circle
			(at 7.499 -6.5 180)
			(size 0.5 0.5)
			(layers "F.Cu" "F.Mask" "F.Paste")
			(net 454 "unconnected-(U4C-IO_L19N_T3_A09_D25_VREF_14-PadG21)")
			(pinfunction "IO_L19N_T3_A09_D25_VREF_14")
			(pintype "bidirectional+no_connect")
			(die_length 18.813)
		)
		(pad "G22" smd circle
			(at 8.499 -6.5 180)
			(size 0.5 0.5)
			(layers "F.Cu" "F.Mask" "F.Paste")
			(net 455 "unconnected-(U4C-IO_L13P_T2_MRCC_14-PadG22)")
			(pinfunction "IO_L13P_T2_MRCC_14")
			(pintype "bidirectional+no_connect")
			(die_length 18.389)
		)
		(pad "G23" smd circle
			(at 9.499 -6.5 180)
			(size 0.5 0.5)
			(layers "F.Cu" "F.Mask" "F.Paste")
			(net 200 "+3V3")
			(pinfunction "VCCO_14")
			(pintype "passive")
		)
		(pad "G24" smd circle
			(at 10.499 -6.5 180)
			(size 0.5 0.5)
			(layers "F.Cu" "F.Mask" "F.Paste")
			(net 688 "/FPGA bank 14/FPGA_PWR.SDA")
			(pinfunction "IO_L14P_T2_SRCC_14")
			(pintype "bidirectional")
			(die_length 19.02)
		)
		(pad "G25" smd circle
			(at 11.499 -6.5 180)
			(size 0.5 0.5)
			(layers "F.Cu" "F.Mask" "F.Paste")
			(net 655 "/Debug FTDI/AUX.RST")
			(pinfunction "IO_L16P_T2_CSI_B_14")
			(pintype "bidirectional")
			(die_length 19.777)
		)
		(pad "G26" smd circle
			(at 12.499 -6.5 180)
			(size 0.5 0.5)
			(layers "F.Cu" "F.Mask" "F.Paste")
			(net 241 "FPGA_POWER_CYCLE")
			(pinfunction "IO_L16N_T2_A15_D31_14")
			(pintype "bidirectional")
			(die_length 19.839)
		)
		(pad "H1" smd circle
			(at -12.5 -5.5 180)
			(size 0.5 0.5)
			(layers "F.Cu" "F.Mask" "F.Paste")
			(net 456 "unconnected-(U4I-MGTXTXN3_115-PadH1)")
			(pinfunction "MGTXTXN3_115")
			(pintype "bidirectional+no_connect")
			(die_length 13.778)
		)
		(pad "H2" smd circle
			(at -11.5 -5.5 180)
			(size 0.5 0.5)
			(layers "F.Cu" "F.Mask" "F.Paste")
			(net 457 "unconnected-(U4I-MGTXTXP3_115-PadH2)")
			(pinfunction "MGTXTXP3_115")
			(pintype "bidirectional+no_connect")
			(die_length 13.817)
		)
		(pad "H3" smd circle
			(at -10.5 -5.5 180)
			(size 0.5 0.5)
			(layers "F.Cu" "F.Mask" "F.Paste")
			(net 226 "+1V2_MGTAVTT")
			(pinfunction "MGTAVTT")
			(pintype "passive")
		)
		(pad "H4" smd circle
			(at -9.5 -5.5 180)
			(size 0.5 0.5)
			(layers "F.Cu" "F.Mask" "F.Paste")
			(net 1 "GND")
			(pinfunction "GND")
			(pintype "passive")
		)
		(pad "H5" smd circle
			(at -8.5 -5.5 180)
			(size 0.5 0.5)
			(layers "F.Cu" "F.Mask" "F.Paste")
			(net 458 "unconnected-(U4I-MGTREFCLK0N_115-PadH5)")
			(pinfunction "MGTREFCLK0N_115")
			(pintype "bidirectional+no_connect")
			(die_length 11.598)
		)
		(pad "H6" smd circle
			(at -7.5 -5.5 180)
			(size 0.5 0.5)
			(layers "F.Cu" "F.Mask" "F.Paste")
			(net 459 "unconnected-(U4I-MGTREFCLK0P_115-PadH6)")
			(pinfunction "MGTREFCLK0P_115")
			(pintype "bidirectional+no_connect")
			(die_length 11.559)
		)
		(pad "H7" smd circle
			(at -6.5 -5.5 180)
			(size 0.5 0.5)
			(layers "F.Cu" "F.Mask" "F.Paste")
			(net 1 "GND")
			(pinfunction "GND")
			(pintype "passive")
		)
		(pad "H8" smd circle
			(at -5.5 -5.5 180)
			(size 0.5 0.5)
			(layers "F.Cu" "F.Mask" "F.Paste")
			(net 460 "unconnected-(U4E-IO_L1N_T0_16-PadH8)")
			(pinfunction "IO_L1N_T0_16")
			(pintype "bidirectional+no_connect")
			(die_length 16.747)
		)
		(pad "H9" smd circle
			(at -4.5 -5.5 180)
			(size 0.5 0.5)
			(layers "F.Cu" "F.Mask" "F.Paste")
			(net 461 "unconnected-(U4E-IO_L1P_T0_16-PadH9)")
			(pinfunction "IO_L1P_T0_16")
			(pintype "bidirectional+no_connect")
			(die_length 15.601)
		)
		(pad "H10" smd circle
			(at -3.5 -5.5 180)
			(size 0.5 0.5)
			(layers "F.Cu" "F.Mask" "F.Paste")
			(net 200 "+3V3")
			(pinfunction "VCCO_16")
			(pintype "passive")
		)
		(pad "H11" smd circle
			(at -2.5 -5.5 180)
			(size 0.5 0.5)
			(layers "F.Cu" "F.Mask" "F.Paste")
			(net 462 "unconnected-(U4E-IO_L6N_T0_VREF_16-PadH11)")
			(pinfunction "IO_L6N_T0_VREF_16")
			(pintype "bidirectional+no_connect")
			(die_length 14.821)
		)
		(pad "H12" smd circle
			(at -1.5 -5.5 180)
			(size 0.5 0.5)
			(layers "F.Cu" "F.Mask" "F.Paste")
			(net 463 "unconnected-(U4E-IO_L6P_T0_16-PadH12)")
			(pinfunction "IO_L6P_T0_16")
			(pintype "bidirectional+no_connect")
			(die_length 13.516)
		)
		(pad "H13" smd circle
			(at -0.5 -5.5 180)
			(size 0.5 0.5)
			(layers "F.Cu" "F.Mask" "F.Paste")
			(net 464 "unconnected-(U4E-IO_L3N_T0_DQS_16-PadH13)")
			(pinfunction "IO_L3N_T0_DQS_16")
			(pintype "bidirectional+no_connect")
			(die_length 12.402)
		)
		(pad "H14" smd circle
			(at 0.499 -5.5 180)
			(size 0.5 0.5)
			(layers "F.Cu" "F.Mask" "F.Paste")
			(net 465 "unconnected-(U4E-IO_L5P_T0_16-PadH14)")
			(pinfunction "IO_L5P_T0_16")
			(pintype "bidirectional+no_connect")
			(die_length 10.698)
		)
		(pad "H15" smd circle
			(at 1.499 -5.5 180)
			(size 0.5 0.5)
			(layers "F.Cu" "F.Mask" "F.Paste")
			(net 1 "GND")
			(pinfunction "GND")
			(pintype "passive")
		)
		(pad "H16" smd circle
			(at 2.499 -5.5 180)
			(size 0.5 0.5)
			(layers "F.Cu" "F.Mask" "F.Paste")
			(net 466 "unconnected-(U4D-IO_L7P_T1_AD10P_15-PadH16)")
			(pinfunction "IO_L7P_T1_AD10P_15")
			(pintype "bidirectional+no_connect")
			(die_length 14.081)
		)
	)
)
